# S9S_MB_2U (Grand Teton) — schematic netlist excerpt (pin names and nets, part order shuffled) for the footprints in the layout excerpt that follows; sources: Cadence DE-HDL packaged netlist, KiCad conversion of 03242023_DA0F0TMBIJ0_F0T_Motherboard_J_brd_V01_OCP.brd

PC560_P1_2  Q_CAP  3300PF 50V 10% X7R  pkg 0402  page 285 : A = SW_P12V_PVCCIN_CPU1_FLT ; B = GND
PC488  Q_CAP  100NF 50V 10% X7R  pkg C0402  page 288 : A = SW_PVCCIN_CPU1_BOOT7_R ; B = SW_PVCCIN_CPU1_BOOTR7

(kicad_pcb
	(version 20260206)
	(generator "pcbnew")
	(generator_version "10.0")
	(general
		(thickness 1.6)
		(legacy_teardrops no)
	)
	(paper "A4")
	(title_block
		(title "03242023_DA0F0TMBIJ0_F0T_Motherboard_J_brd_V01_OCP.brd")
		(comment 1 "Grand Teton / footprints 984-985 of 6105")
	)
	(layers
		(0 "F.Cu" signal "TOP")
		(4 "In1.Cu" signal "GND")
		(6 "In2.Cu" signal "IN1")
		(8 "In3.Cu" signal "GND1")
		(10 "In4.Cu" signal "IN2")
		(12 "In5.Cu" signal "GND2")
		(14 "In6.Cu" signal "IN3")
		(16 "In7.Cu" signal "GND3")
		(18 "In8.Cu" signal "VCC")
		(20 "In9.Cu" signal "VCC1")
		(22 "In10.Cu" signal "GND4")
		(24 "In11.Cu" signal "IN4")
		(26 "In12.Cu" signal "GND5")
		(28 "In13.Cu" signal "IN5")
		(30 "In14.Cu" signal "GND6")
		(32 "In15.Cu" signal "IN6")
		(34 "In16.Cu" signal "GND7")
		(2 "B.Cu" signal "BOTTOM")
		(9 "F.Adhes" user "F.Adhesive")
		(11 "B.Adhes" user "B.Adhesive")
		(13 "F.Paste" user "Package Geometry/Pastemask Top")
		(15 "B.Paste" user "Package Geometry/Pastemask Bottom")
		(5 "F.SilkS" user "Ref Des/Silkscreen Top")
		(7 "B.SilkS" user "Ref Des/Silkscreen Bottom")
		(1 "F.Mask" user "Board Geometry/Soldermask Top")
		(3 "B.Mask" user "Board Geometry/Soldermask Bottom")
		(17 "Dwgs.User" user "User.Drawings")
		(19 "Cmts.User" user "User.Comments")
		(21 "Eco1.User" user "User.Eco1")
		(23 "Eco2.User" user "User.Eco2")
		(25 "Edge.Cuts" user "Board Geometry/Outline")
		(27 "Margin" user)
		(31 "F.CrtYd" user "Package Geometry/Place Bound Top")
		(29 "B.CrtYd" user "Package Geometry/Place Bound Bottom")
		(35 "F.Fab" user "Ref Des/Assembly Top")
		(33 "B.Fab" user "Ref Des/Assembly Bottom")
	)
	(footprint ""
		(layer "F.Cu")
		(at 82.462624 -347.520514 -90)
		(property "Reference" "PC488"
			(at 0 0 270)
			(layer "F.SilkS")
			(hide yes)
			(effects
				(font
					(size 1.27 1.27)
				)
			)
		)
		(property "Value" ""
			(at 0 0 270)
			(layer "F.Fab")
			(effects
				(font
					(size 1.27 1.27)
				)
			)
		)
		(duplicate_pad_numbers_are_jumpers no)
		(fp_line
			(start -0.7874 0.4064)
			(end -0.7874 -0.4064)
			(stroke
				(width 0.1524)
				(type default)
			)
			(layer "F.SilkS")
		)
		(fp_line
			(start 0.7874 0.4064)
			(end -0.7874 0.4064)
			(stroke
				(width 0.1524)
				(type default)
			)
			(layer "F.SilkS")
		)
		(fp_line
			(start -0.7874 -0.4064)
			(end 0.7874 -0.4064)
			(stroke
				(width 0.1524)
				(type default)
			)
			(layer "F.SilkS")
		)
		(fp_line
			(start 0.7874 -0.4064)
			(end 0.7874 0.4064)
			(stroke
				(width 0.1524)
				(type default)
			)
			(layer "F.SilkS")
		)
		(fp_line
			(start -0.67945 0.3048)
			(end -0.67945 -0.305054)
			(stroke
				(width 0.1)
				(type default)
			)
			(layer "F.Fab")
		)
		(fp_line
			(start -0.12065 0.3048)
			(end -0.67945 0.3048)
			(stroke
				(width 0.1)
				(type default)
			)
			(layer "F.Fab")
		)
		(fp_line
			(start 0.120396 0.3048)
			(end 0.120396 0.2794)
			(stroke
				(width 0.1)
				(type default)
			)
			(layer "F.Fab")
		)
		(fp_line
			(start 0.67945 0.3048)
			(end 0.120396 0.3048)
			(stroke
				(width 0.1)
				(type default)
			)
			(layer "F.Fab")
		)
		(fp_line
			(start -0.12065 0.2794)
			(end -0.12065 0.3048)
			(stroke
				(width 0.1)
				(type default)
			)
			(layer "F.Fab")
		)
		(fp_line
			(start 0.120396 0.2794)
			(end -0.12065 0.2794)
			(stroke
				(width 0.1)
				(type default)
			)
			(layer "F.Fab")
		)
		(fp_line
			(start -0.12065 -0.2794)
			(end 0.12065 -0.2794)
			(stroke
				(width 0.1)
				(type default)
			)
			(layer "F.Fab")
		)
		(fp_line
			(start 0.12065 -0.2794)
			(end 0.12065 -0.3048)
			(stroke
				(width 0.1)
				(type default)
			)
			(layer "F.Fab")
		)
		(fp_line
			(start 0.12065 -0.3048)
			(end 0.67945 -0.3048)
			(stroke
				(width 0.1)
				(type default)
			)
			(layer "F.Fab")
		)
		(fp_line
			(start 0.67945 -0.3048)
			(end 0.67945 0.3048)
			(stroke
				(width 0.1)
				(type default)
			)
			(layer "F.Fab")
		)
		(fp_line
			(start -0.67945 -0.305054)
			(end -0.12065 -0.305054)
			(stroke
				(width 0.1)
				(type default)
			)
			(layer "F.Fab")
		)
		(fp_line
			(start -0.12065 -0.305054)
			(end -0.12065 -0.2794)
			(stroke
				(width 0.1)
				(type default)
			)
			(layer "F.Fab")
		)
		(pad "1" smd circle
			(at -0.40005 0 270)
			(size 0 0)
			(layers "F.Cu" "F.Mask" "F.Paste")
			(net "SW_PVCCIN_CPU1_BOOT7_R")
		)
		(pad "2" smd circle
			(at 0.40005 0 270)
			(size 0 0)
			(layers "F.Cu" "F.Mask" "F.Paste")
			(net "SW_PVCCIN_CPU1_BOOTR7")
		)
	)
	(footprint ""
		(layer "F.Cu")
		(at 109.00537 -337.830668)
		(property "Reference" "PC560_P1_2"
			(at 0 0 0)
			(layer "F.SilkS")
			(hide yes)
			(effects
				(font
					(size 1.27 1.27)
				)
			)
		)
		(property "Value" ""
			(at 0 0 0)
			(layer "F.Fab")
			(effects
				(font
					(size 1.27 1.27)
				)
			)
		)
		(duplicate_pad_numbers_are_jumpers no)
		(fp_line
			(start -0.7874 -0.4064)
			(end 0.7874 -0.4064)
			(stroke
				(width 0.1524)
				(type default)
			)
			(layer "F.SilkS")
		)
		(fp_line
			(start -0.7874 0.4064)
			(end -0.7874 -0.4064)
			(stroke
				(width 0.1524)
				(type default)
			)
			(layer "F.SilkS")
		)
		(fp_line
			(start 0.7874 -0.4064)
			(end 0.7874 0.4064)
			(stroke
				(width 0.1524)
				(type default)
			)
			(layer "F.SilkS")
		)
		(fp_line
			(start 0.7874 0.4064)
			(end -0.7874 0.4064)
			(stroke
				(width 0.1524)
				(type default)
			)
			(layer "F.SilkS")
		)
		(fp_line
			(start -0.67945 -0.305054)
			(end -0.12065 -0.305054)
			(stroke
				(width 0.1)
				(type default)
			)
			(layer "F.Fab")
		)
		(fp_line
			(start -0.67945 0.3048)
			(end -0.67945 -0.305054)
			(stroke
				(width 0.1)
				(type default)
			)
			(layer "F.Fab")
		)
		(fp_line
			(start -0.12065 -0.305054)
			(end -0.12065 -0.2794)
			(stroke
				(width 0.1)
				(type default)
			)
			(layer "F.Fab")
		)
		(fp_line
			(start -0.12065 -0.2794)
			(end 0.12065 -0.2794)
			(stroke
				(width 0.1)
				(type default)
			)
			(layer "F.Fab")
		)
		(fp_line
			(start -0.12065 0.2794)
			(end -0.12065 0.3048)
			(stroke
				(width 0.1)
				(type default)
			)
			(layer "F.Fab")
		)
		(fp_line
			(start -0.12065 0.3048)
			(end -0.67945 0.3048)
			(stroke
				(width 0.1)
				(type default)
			)
			(layer "F.Fab")
		)
		(fp_line
			(start 0.120396 0.2794)
			(end -0.12065 0.2794)
			(stroke
				(width 0.1)
				(type default)
			)
			(layer "F.Fab")
		)
		(fp_line
			(start 0.120396 0.3048)
			(end 0.120396 0.2794)
			(stroke
				(width 0.1)
				(type default)
			)
			(layer "F.Fab")
		)
		(fp_line
			(start 0.12065 -0.3048)
			(end 0.67945 -0.3048)
			(stroke
				(width 0.1)
				(type default)
			)
			(layer "F.Fab")
		)
		(fp_line
			(start 0.12065 -0.2794)
			(end 0.12065 -0.3048)
			(stroke
				(width 0.1)
				(type default)
			)
			(layer "F.Fab")
		)
		(fp_line
			(start 0.67945 -0.3048)
			(end 0.67945 0.3048)
			(stroke
				(width 0.1)
				(type default)
			)
			(layer "F.Fab")
		)
		(fp_line
			(start 0.67945 0.3048)
			(end 0.120396 0.3048)
			(stroke
				(width 0.1)
				(type default)
			)
			(layer "F.Fab")
		)
		(pad "1" smd circle
			(at -0.40005 0)
			(size 0 0)
			(layers "F.Cu" "F.Mask" "F.Paste")
			(net "SW_P12V_PVCCIN_CPU1_FLT")
		)
		(pad "2" smd circle
			(at 0.40005 0)
			(size 0 0)
			(layers "F.Cu" "F.Mask" "F.Paste")
			(net "GND")
		)
	)
)
